#ISCELL
  mstr_misc dns *
  *
#ISCELL
  pure_quanta quanta_title_block_c *
  *
#ISCELL
  pure_quanta_power universal_gnd *
  page83_i100
#ISCELL
  pure_quanta_power universal_gnd *
  page83_i101
#ISCELL
  pure_quanta_power universal_gnd *
  page83_i102
#ISCELL
  pure_quanta_power universal_gnd *
  page83_i103
#ISCELL
  pure_quanta_power universal_gnd *
  page83_i104
#ISCELL
  pure_quanta_power universal_gnd *
  page83_i105
#ISCELL
  pure_quanta_power universal_gnd *
  page83_i106
#ISCELL
  pure_quanta_power universal_gnd *
  page83_i107
#ISCELL
  pure_quanta_power universal_gnd *
  page83_i108
#ISCELL
  pure_quanta_power universal_gnd *
  page83_i109
#ISCELL
  pure_quanta_power universal_gnd *
  page83_i110
#ISCELL
  pure_quanta_power universal_gnd *
  page83_i111
#ISCELL
  pure_quanta_power universal_gnd *
  page83_i112
#ISCELL
  pure_quanta_power universal_gnd *
  page83_i113
#ISCELL
  pure_quanta_power universal_gnd *
  page83_i114
#CELL
  pure_quanta q_res *
  page83_i115
#CELL
  pure_quanta q_res *
  page83_i116
#CELL
  pure_quanta q_res *
  page83_i117
#CELL
  pure_quanta q_res *
  page83_i118
#CELL
  pure_quanta q_res *
  page83_i119
#CELL
  pure_quanta q_res *
  page83_i120
#CELL
  pure_quanta q_res *
  page83_i121
#CELL
  pure_quanta q_res *
  page83_i122
#CELL
  pure_quanta q_res *
  page83_i131
#CELL
  pure_quanta q_res *
  page83_i132
#CELL
  pure_quanta q_res *
  page83_i133
#CELL
  pure_quanta q_res *
  page83_i134
#CELL
  pure_quanta q_res *
  page83_i135
#CELL
  pure_quanta q_res *
  page83_i136
#CELL
  pure_quanta q_res *
  page83_i137
#CELL
  pure_quanta q_res *
  page83_i138
#CELL
  pure_quanta q_res *
  page83_i139
#CELL
  pure_quanta q_res *
  page83_i140
#CELL
  pure_quanta q_res *
  page83_i141
#CELL
  pure_quanta q_res *
  page83_i142
#ISCELL
  standard offpage *
  page83_i2
#CELL
  pure_quanta q_res *
  page83_i22
#ISCELL
  pure_quanta_power universal_gnd *
  page83_i23
#CELL
  pure_quanta q_cap *
  page83_i24
#ISCELL
  pure_quanta_power universal_power *
  page83_i25
#CELL
  pure_quanta sn74lvc1g07dbvr *
  page83_i26
#CELL
  pure_quanta q_res *
  page83_i27
#ISCELL
  standard offpage *
  page83_i28
#CELL
  pure_quanta q_res *
  page83_i29
#ISCELL
  pure_quanta_power universal_power *
  page83_i30
#CELL
  pure_quanta q_res *
  page83_i36
#CELL
  pure_quanta q_res *
  page83_i39
#ISCELL
  pure_quanta_power universal_power *
  page83_i40
#CELL
  pure_quanta q_res *
  page83_i46
#ISCELL
  pure_quanta_power universal_power *
  page83_i48
#CELL
  pure_quanta q_res *
  page83_i50
#CELL
  pure_quanta q_res *
  page83_i52
#CELL
  pure_quanta q_res *
  page83_i54
#CELL
  pure_quanta q_res *
  page83_i55
#CELL
  pure_quanta q_res *
  page83_i56
#ISCELL
  standard offpage *
  page83_i57
#ISCELL
  standard offpage *
  page83_i58
#ISCELL
  standard offpage *
  page83_i59
#ISCELL
  standard offpage *
  page83_i60
#ISCELL
  standard offpage *
  page83_i61
#CELL
  pure_quanta q_res *
  page83_i64
#CELL
  pure_quanta q_res *
  page83_i65
#ISCELL
  standard offpage *
  page83_i66
#ISCELL
  standard offpage *
  page83_i67
#ISCELL
  standard offpage *
  page83_i68
#ISCELL
  standard offpage *
  page83_i69
#ISCELL
  standard offpage *
  page83_i70
#CELL
  pure_quanta q_res *
  page83_i71
#CELL
  pure_quanta q_res *
  page83_i72
#ISCELL
  pure_quanta_power universal_power *
  page83_i82
#ISCELL
  pure_quanta_power universal_gnd *
  page83_i9
#ISCELL
  standard offpage *
  page83_i92
#ISCELL
  standard offpage *
  page83_i93
#ISCELL
  standard offpage *
  page83_i94
#ISCELL
  standard offpage *
  page83_i95
#ISCELL
  standard offpage *
  page83_i96
#ISCELL
  pure_quanta_power universal_power *
  page83_i97
#ISCELL
  standard offpage *
  page83_i98
#ISCELL
  pure_quanta_power universal_gnd *
  page83_i99
